(kicad_pcb
	(version 20260206)
	(generator "pcbnew")
	(generator_version "10.0")
	(general
		(thickness 1.6)
		(legacy_teardrops no)
	)
	(paper "A4")
	(title_block
		(title "12092022_DA0F0TFB6D0_F0T_FAN_BOARD_MP5048_D_brd_v02_OCP.brd")
		(comment 1 "Grand Teton / footprints 393-397 of 924")
	)
	(layers
		(0 "F.Cu" signal "TOP")
		(4 "In1.Cu" signal "GND")
		(6 "In2.Cu" signal "IN1")
		(8 "In3.Cu" signal "IN2")
		(10 "In4.Cu" signal "GND1")
		(2 "B.Cu" signal "BOTTOM")
		(9 "F.Adhes" user "F.Adhesive")
		(11 "B.Adhes" user "B.Adhesive")
		(13 "F.Paste" user "Package Geometry/Pastemask Top")
		(15 "B.Paste" user "Package Geometry/Pastemask Bottom")
		(5 "F.SilkS" user "Ref Des/Silkscreen Top")
		(7 "B.SilkS" user "Ref Des/Silkscreen Bottom")
		(1 "F.Mask" user "Board Geometry/Soldermask Top")
		(3 "B.Mask" user "Board Geometry/Soldermask Bottom")
		(17 "Dwgs.User" user "User.Drawings")
		(19 "Cmts.User" user "User.Comments")
		(21 "Eco1.User" user "User.Eco1")
		(23 "Eco2.User" user "User.Eco2")
		(25 "Edge.Cuts" user "Board Geometry/Outline")
		(27 "Margin" user)
		(31 "F.CrtYd" user "Package Geometry/Place Bound Top")
		(29 "B.CrtYd" user "Package Geometry/Place Bound Bottom")
		(35 "F.Fab" user "Ref Des/Assembly Top")
		(33 "B.Fab" user "Ref Des/Assembly Bottom")
	)
	(footprint ""
		(layer "F.Cu")
		(at 15.377922 -210.125056 180)
		(property "Reference" "D140"
			(at 5.852922 -0.093726 0)
			(unlocked yes)
			(layer "F.SilkS")
			(effects
				(font
					(size 0.7874 0.5842)
					(thickness 0.1524)
				)
				(justify left)
			)
		)
		(property "Value" ""
			(at 0 0 180)
			(layer "F.Fab")
			(effects
				(font
					(size 1.27 1.27)
				)
			)
		)
		(duplicate_pad_numbers_are_jumpers no)
		(fp_line
			(start 1.778 0.6858)
			(end 1.778 -0.6858)
			(stroke
				(width 0.1524)
				(type default)
			)
			(layer "F.SilkS")
		)
		(fp_line
			(start 1.738122 0.7112)
			(end -1.651 0.7112)
			(stroke
				(width 0.1524)
				(type default)
			)
			(layer "F.SilkS")
		)
		(fp_line
			(start 1.651 -0.6858)
			(end 1.651 0.6858)
			(stroke
				(width 0.1524)
				(type default)
			)
			(layer "F.SilkS")
		)
		(fp_line
			(start 0.299974 -0.500126)
			(end 0.299974 0.500126)
			(stroke
				(width 0.1524)
				(type default)
			)
			(layer "F.SilkS")
		)
		(fp_line
			(start 0.199898 0)
			(end -0.299974 -0.500126)
			(stroke
				(width 0.1524)
				(type default)
			)
			(layer "F.SilkS")
		)
		(fp_line
			(start -0.299974 0.500126)
			(end 0.199898 0)
			(stroke
				(width 0.1524)
				(type default)
			)
			(layer "F.SilkS")
		)
		(fp_line
			(start -0.299974 -0.500126)
			(end -0.299974 0.500126)
			(stroke
				(width 0.1524)
				(type default)
			)
			(layer "F.SilkS")
		)
		(fp_line
			(start -1.651 0.7112)
			(end -1.651 -0.7112)
			(stroke
				(width 0.1524)
				(type default)
			)
			(layer "F.SilkS")
		)
		(fp_line
			(start -1.651 -0.7112)
			(end 1.738122 -0.7112)
			(stroke
				(width 0.1524)
				(type default)
			)
			(layer "F.SilkS")
		)
		(fp_line
			(start 1.35001 0.175006)
			(end 0.899922 0.175006)
			(stroke
				(width 0.1)
				(type default)
			)
			(layer "F.Fab")
		)
		(fp_line
			(start 1.35001 -0.225044)
			(end 1.35001 0.175006)
			(stroke
				(width 0.1)
				(type default)
			)
			(layer "F.Fab")
		)
		(fp_line
			(start 0.899922 0.700024)
			(end -0.899922 0.700024)
			(stroke
				(width 0.1)
				(type default)
			)
			(layer "F.Fab")
		)
		(fp_line
			(start 0.899922 0.175006)
			(end 0.899922 0.700024)
			(stroke
				(width 0.1)
				(type default)
			)
			(layer "F.Fab")
		)
		(fp_line
			(start 0.899922 -0.225044)
			(end 1.35001 -0.225044)
			(stroke
				(width 0.1)
				(type default)
			)
			(layer "F.Fab")
		)
		(fp_line
			(start 0.899922 -0.700024)
			(end 0.899922 -0.225044)
			(stroke
				(width 0.1)
				(type default)
			)
			(layer "F.Fab")
		)
		(fp_line
			(start 0.299974 -0.500126)
			(end 0.299974 0.500126)
			(stroke
				(width 0.1)
				(type default)
			)
			(layer "F.Fab")
		)
		(fp_line
			(start 0.199898 0)
			(end -0.299974 -0.500126)
			(stroke
				(width 0.1)
				(type default)
			)
			(layer "F.Fab")
		)
		(fp_line
			(start -0.299974 0.500126)
			(end 0.199898 0)
			(stroke
				(width 0.1)
				(type default)
			)
			(layer "F.Fab")
		)
		(fp_line
			(start -0.299974 -0.500126)
			(end -0.299974 0.500126)
			(stroke
				(width 0.1)
				(type default)
			)
			(layer "F.Fab")
		)
		(fp_line
			(start -0.899922 0.700024)
			(end -0.899922 0.175006)
			(stroke
				(width 0.1)
				(type default)
			)
			(layer "F.Fab")
		)
		(fp_line
			(start -0.899922 0.175006)
			(end -1.35001 0.175006)
			(stroke
				(width 0.1)
				(type default)
			)
			(layer "F.Fab")
		)
		(fp_line
			(start -0.899922 -0.225044)
			(end -0.899922 -0.700024)
			(stroke
				(width 0.1)
				(type default)
			)
			(layer "F.Fab")
		)
		(fp_line
			(start -0.899922 -0.700024)
			(end 0.899922 -0.700024)
			(stroke
				(width 0.1)
				(type default)
			)
			(layer "F.Fab")
		)
		(fp_line
			(start -1.35001 0.175006)
			(end -1.35001 -0.225044)
			(stroke
				(width 0.1)
				(type default)
			)
			(layer "F.Fab")
		)
		(fp_line
			(start -1.35001 -0.225044)
			(end -0.899922 -0.225044)
			(stroke
				(width 0.1)
				(type default)
			)
			(layer "F.Fab")
		)
		(fp_text user "-"
			(at 1.026922 0.853694 180)
			(unlocked yes)
			(layer "F.SilkS")
			(effects
				(font
					(size 1.905 1.4224)
					(thickness 0.1524)
				)
				(justify left)
			)
		)
		(fp_text user "+"
			(at -2.656078 -1.178306 180)
			(unlocked yes)
			(layer "F.SilkS")
			(effects
				(font
					(size 1.905 1.4224)
					(thickness 0.1524)
				)
				(justify left)
			)
		)
		(fp_text user "-"
			(at 1.8288 -0.24765 180)
			(unlocked yes)
			(layer "F.Fab")
			(effects
				(font
					(size 1.905 1.4224)
					(thickness 0.1524)
				)
				(justify left)
			)
		)
		(fp_text user "+"
			(at -2.794 -0.19685 180)
			(unlocked yes)
			(layer "F.Fab")
			(effects
				(font
					(size 1.905 1.4224)
					(thickness 0.1524)
				)
				(justify left)
			)
		)
		(pad "1" smd rect
			(at -1.0922 0)
			(size 0.8128 0.8636)
			(layers "F.Cu" "F.Mask" "F.Paste")
			(net "FAN_6_TACH_OL_R")
		)
		(pad "2" smd rect
			(at 1.0922 0 180)
			(size 0.8128 0.8636)
			(layers "F.Cu" "F.Mask" "F.Paste")
			(net "FAN_6_TACH_OL_D")
		)
	)
	(footprint ""
		(layer "F.Cu")
		(at 13.589 -203.073 90)
		(property "Reference" "R5700"
			(at 0 0 90)
			(layer "F.SilkS")
			(hide yes)
			(effects
				(font
					(size 1.27 1.27)
				)
			)
		)
		(property "Value" ""
			(at 0 0 90)
			(layer "F.Fab")
			(effects
				(font
					(size 1.27 1.27)
				)
			)
		)
		(duplicate_pad_numbers_are_jumpers no)
		(fp_line
			(start 0.7874 -0.4064)
			(end 0.7874 0.4064)
			(stroke
				(width 0.1524)
				(type default)
			)
			(layer "F.SilkS")
		)
		(fp_line
			(start -0.7874 -0.4064)
			(end 0.7874 -0.4064)
			(stroke
				(width 0.1524)
				(type default)
			)
			(layer "F.SilkS")
		)
		(fp_line
			(start 0.7874 0.4064)
			(end -0.7874 0.4064)
			(stroke
				(width 0.1524)
				(type default)
			)
			(layer "F.SilkS")
		)
		(fp_line
			(start -0.7874 0.4064)
			(end -0.7874 -0.4064)
			(stroke
				(width 0.1524)
				(type default)
			)
			(layer "F.SilkS")
		)
		(fp_line
			(start -0.12065 -0.305054)
			(end -0.12065 -0.2794)
			(stroke
				(width 0.1)
				(type default)
			)
			(layer "F.Fab")
		)
		(fp_line
			(start -0.67945 -0.305054)
			(end -0.12065 -0.305054)
			(stroke
				(width 0.1)
				(type default)
			)
			(layer "F.Fab")
		)
		(fp_line
			(start 0.67945 -0.3048)
			(end 0.67945 0.3048)
			(stroke
				(width 0.1)
				(type default)
			)
			(layer "F.Fab")
		)
		(fp_line
			(start 0.12065 -0.3048)
			(end 0.67945 -0.3048)
			(stroke
				(width 0.1)
				(type default)
			)
			(layer "F.Fab")
		)
		(fp_line
			(start 0.12065 -0.2794)
			(end 0.12065 -0.3048)
			(stroke
				(width 0.1)
				(type default)
			)
			(layer "F.Fab")
		)
		(fp_line
			(start -0.12065 -0.2794)
			(end 0.12065 -0.2794)
			(stroke
				(width 0.1)
				(type default)
			)
			(layer "F.Fab")
		)
		(fp_line
			(start 0.120396 0.2794)
			(end -0.12065 0.2794)
			(stroke
				(width 0.1)
				(type default)
			)
			(layer "F.Fab")
		)
		(fp_line
			(start -0.12065 0.2794)
			(end -0.12065 0.3048)
			(stroke
				(width 0.1)
				(type default)
			)
			(layer "F.Fab")
		)
		(fp_line
			(start 0.67945 0.3048)
			(end 0.120396 0.3048)
			(stroke
				(width 0.1)
				(type default)
			)
			(layer "F.Fab")
		)
		(fp_line
			(start 0.120396 0.3048)
			(end 0.120396 0.2794)
			(stroke
				(width 0.1)
				(type default)
			)
			(layer "F.Fab")
		)
		(fp_line
			(start -0.12065 0.3048)
			(end -0.67945 0.3048)
			(stroke
				(width 0.1)
				(type default)
			)
			(layer "F.Fab")
		)
		(fp_line
			(start -0.67945 0.3048)
			(end -0.67945 -0.305054)
			(stroke
				(width 0.1)
				(type default)
			)
			(layer "F.Fab")
		)
		(pad "1" smd rect
			(at -0.40005 0 270)
			(size 0.4572 0.508)
			(layers "F.Cu" "F.Mask" "F.Paste")
			(net "P12V_LED_R_FAN6")
		)
		(pad "2" smd rect
			(at 0.40005 0 270)
			(size 0.4572 0.508)
			(layers "F.Cu" "F.Mask" "F.Paste")
			(net "P12V_LED_R1_FAN6")
		)
	)
	(footprint ""
		(layer "F.Cu")
		(at 14.0589 -123.317 180)
		(property "Reference" "R5586"
			(at 0 0 180)
			(layer "F.SilkS")
			(hide yes)
			(effects
				(font
					(size 1.27 1.27)
				)
			)
		)
		(property "Value" ""
			(at 0 0 180)
			(layer "F.Fab")
			(effects
				(font
					(size 1.27 1.27)
				)
			)
		)
		(duplicate_pad_numbers_are_jumpers no)
		(fp_line
			(start 0.7874 0.4064)
			(end -0.7874 0.4064)
			(stroke
				(width 0.1524)
				(type default)
			)
			(layer "F.SilkS")
		)
		(fp_line
			(start 0.7874 -0.4064)
			(end 0.7874 0.4064)
			(stroke
				(width 0.1524)
				(type default)
			)
			(layer "F.SilkS")
		)
		(fp_line
			(start -0.7874 0.4064)
			(end -0.7874 -0.4064)
			(stroke
				(width 0.1524)
				(type default)
			)
			(layer "F.SilkS")
		)
		(fp_line
			(start -0.7874 -0.4064)
			(end 0.7874 -0.4064)
			(stroke
				(width 0.1524)
				(type default)
			)
			(layer "F.SilkS")
		)
		(fp_line
			(start 0.67945 0.3048)
			(end 0.120396 0.3048)
			(stroke
				(width 0.1)
				(type default)
			)
			(layer "F.Fab")
		)
		(fp_line
			(start 0.67945 -0.3048)
			(end 0.67945 0.3048)
			(stroke
				(width 0.1)
				(type default)
			)
			(layer "F.Fab")
		)
		(fp_line
			(start 0.12065 -0.2794)
			(end 0.12065 -0.3048)
			(stroke
				(width 0.1)
				(type default)
			)
			(layer "F.Fab")
		)
		(fp_line
			(start 0.12065 -0.3048)
			(end 0.67945 -0.3048)
			(stroke
				(width 0.1)
				(type default)
			)
			(layer "F.Fab")
		)
		(fp_line
			(start 0.120396 0.3048)
			(end 0.120396 0.2794)
			(stroke
				(width 0.1)
				(type default)
			)
			(layer "F.Fab")
		)
		(fp_line
			(start 0.120396 0.2794)
			(end -0.12065 0.2794)
			(stroke
				(width 0.1)
				(type default)
			)
			(layer "F.Fab")
		)
		(fp_line
			(start -0.12065 0.3048)
			(end -0.67945 0.3048)
			(stroke
				(width 0.1)
				(type default)
			)
			(layer "F.Fab")
		)
		(fp_line
			(start -0.12065 0.2794)
			(end -0.12065 0.3048)
			(stroke
				(width 0.1)
				(type default)
			)
			(layer "F.Fab")
		)
		(fp_line
			(start -0.12065 -0.2794)
			(end 0.12065 -0.2794)
			(stroke
				(width 0.1)
				(type default)
			)
			(layer "F.Fab")
		)
		(fp_line
			(start -0.12065 -0.305054)
			(end -0.12065 -0.2794)
			(stroke
				(width 0.1)
				(type default)
			)
			(layer "F.Fab")
		)
		(fp_line
			(start -0.67945 0.3048)
			(end -0.67945 -0.305054)
			(stroke
				(width 0.1)
				(type default)
			)
			(layer "F.Fab")
		)
		(fp_line
			(start -0.67945 -0.305054)
			(end -0.12065 -0.305054)
			(stroke
				(width 0.1)
				(type default)
			)
			(layer "F.Fab")
		)
		(pad "1" smd rect
			(at -0.40005 0)
			(size 0.4572 0.508)
			(layers "F.Cu" "F.Mask" "F.Paste")
			(net "FAN_4_TACH_IL")
		)
		(pad "2" smd rect
			(at 0.40005 0)
			(size 0.4572 0.508)
			(layers "F.Cu" "F.Mask" "F.Paste")
			(net "FAN_4_TACH_IL_R2")
		)
	)
	(footprint ""
		(layer "F.Cu")
		(at 18.669 -291.465 180)
		(property "Reference" "D262"
			(at 2.0193 1.41097 0)
			(unlocked yes)
			(layer "F.SilkS")
			(effects
				(font
					(size 0.7874 0.5842)
					(thickness 0.1524)
				)
				(justify left)
			)
		)
		(property "Value" ""
			(at 0 0 180)
			(layer "F.Fab")
			(effects
				(font
					(size 1.27 1.27)
				)
			)
		)
		(duplicate_pad_numbers_are_jumpers no)
		(fp_line
			(start 0.94488 0.450088)
			(end 0.94488 -0.450088)
			(stroke
				(width 0.1524)
				(type default)
			)
			(layer "F.SilkS")
		)
		(fp_line
			(start 0.94488 -0.450088)
			(end -0.854964 -0.450088)
			(stroke
				(width 0.1524)
				(type default)
			)
			(layer "F.SilkS")
		)
		(fp_line
			(start 0.870458 -0.2794)
			(end 0.845058 0.4064)
			(stroke
				(width 0.1524)
				(type default)
			)
			(layer "F.SilkS")
		)
		(fp_line
			(start 0.845058 0.4064)
			(end 0.845058 -0.381)
			(stroke
				(width 0.1524)
				(type default)
			)
			(layer "F.SilkS")
		)
		(fp_line
			(start -0.854964 0.450088)
			(end 0.925068 0.450088)
			(stroke
				(width 0.1524)
				(type default)
			)
			(layer "F.SilkS")
		)
		(fp_line
			(start -0.854964 -0.450088)
			(end -0.854964 0.450088)
			(stroke
				(width 0.1524)
				(type default)
			)
			(layer "F.SilkS")
		)
		(fp_line
			(start 0.54991 0.350012)
			(end 0.54991 -0.350012)
			(stroke
				(width 0.1)
				(type default)
			)
			(layer "F.Fab")
		)
		(fp_line
			(start 0.54991 -0.350012)
			(end -0.54991 -0.350012)
			(stroke
				(width 0.1)
				(type default)
			)
			(layer "F.Fab")
		)
		(fp_line
			(start -0.54991 0.350012)
			(end 0.54991 0.350012)
			(stroke
				(width 0.1)
				(type default)
			)
			(layer "F.Fab")
		)
		(fp_line
			(start -0.54991 -0.350012)
			(end -0.54991 0.350012)
			(stroke
				(width 0.1)
				(type default)
			)
			(layer "F.Fab")
		)
		(fp_text user "-"
			(at 1.778 0.98425 0)
			(unlocked yes)
			(layer "F.SilkS")
			(effects
				(font
					(size 1.905 1.4224)
					(thickness 0.1524)
				)
				(justify left)
			)
		)
		(fp_text user "+"
			(at -0.635 0.22225 0)
			(unlocked yes)
			(layer "F.SilkS")
			(effects
				(font
					(size 1.905 1.4224)
					(thickness 0.1524)
				)
				(justify left)
			)
		)
		(fp_text user "-"
			(at 2.48539 0.239014 0)
			(unlocked yes)
			(layer "F.Fab")
			(effects
				(font
					(size 1.905 1.4224)
					(thickness 0.1524)
				)
				(justify left)
			)
		)
		(fp_text user "+"
			(at -0.808228 0.239014 0)
			(unlocked yes)
			(layer "F.Fab")
			(effects
				(font
					(size 1.905 1.4224)
					(thickness 0.1524)
				)
				(justify left)
			)
		)
		(pad "A" smd rect
			(at -0.424942 0 180)
			(size 0.5588 0.6096)
			(layers "F.Cu" "F.Mask" "F.Paste")
			(net "GND")
		)
		(pad "C" smd rect
			(at 0.424942 0)
			(size 0.5588 0.6096)
			(layers "F.Cu" "F.Mask" "F.Paste")
			(net "FAN_7_PWM_IL_R")
		)
	)
	(footprint ""
		(layer "F.Cu")
		(at 33.274 -103.632 180)
		(property "Reference" "C2043"
			(at 0 0 180)
			(layer "F.SilkS")
			(hide yes)
			(effects
				(font
					(size 1.27 1.27)
				)
			)
		)
		(property "Value" ""
			(at 0 0 180)
			(layer "F.Fab")
			(effects
				(font
					(size 1.27 1.27)
				)
			)
		)
		(duplicate_pad_numbers_are_jumpers no)
		(fp_line
			(start 0.7874 0.4064)
			(end -0.7874 0.4064)
			(stroke
				(width 0.1524)
				(type default)
			)
			(layer "F.SilkS")
		)
		(fp_line
			(start 0.7874 -0.4064)
			(end 0.7874 0.4064)
			(stroke
				(width 0.1524)
				(type default)
			)
			(layer "F.SilkS")
		)
		(fp_line
			(start -0.7874 0.4064)
			(end -0.7874 -0.4064)
			(stroke
				(width 0.1524)
				(type default)
			)
			(layer "F.SilkS")
		)
		(fp_line
			(start -0.7874 -0.4064)
			(end 0.7874 -0.4064)
			(stroke
				(width 0.1524)
				(type default)
			)
			(layer "F.SilkS")
		)
		(fp_line
			(start 0.67945 0.3048)
			(end 0.120396 0.3048)
			(stroke
				(width 0.1)
				(type default)
			)
			(layer "F.Fab")
		)
		(fp_line
			(start 0.67945 -0.3048)
			(end 0.67945 0.3048)
			(stroke
				(width 0.1)
				(type default)
			)
			(layer "F.Fab")
		)
		(fp_line
			(start 0.12065 -0.2794)
			(end 0.12065 -0.3048)
			(stroke
				(width 0.1)
				(type default)
			)
			(layer "F.Fab")
		)
		(fp_line
			(start 0.12065 -0.3048)
			(end 0.67945 -0.3048)
			(stroke
				(width 0.1)
				(type default)
			)
			(layer "F.Fab")
		)
		(fp_line
			(start 0.120396 0.3048)
			(end 0.120396 0.2794)
			(stroke
				(width 0.1)
				(type default)
			)
			(layer "F.Fab")
		)
		(fp_line
			(start 0.120396 0.2794)
			(end -0.12065 0.2794)
			(stroke
				(width 0.1)
				(type default)
			)
			(layer "F.Fab")
		)
		(fp_line
			(start -0.12065 0.3048)
			(end -0.67945 0.3048)
			(stroke
				(width 0.1)
				(type default)
			)
			(layer "F.Fab")
		)
		(fp_line
			(start -0.12065 0.2794)
			(end -0.12065 0.3048)
			(stroke
				(width 0.1)
				(type default)
			)
			(layer "F.Fab")
		)
		(fp_line
			(start -0.12065 -0.2794)
			(end 0.12065 -0.2794)
			(stroke
				(width 0.1)
				(type default)
			)
			(layer "F.Fab")
		)
		(fp_line
			(start -0.12065 -0.305054)
			(end -0.12065 -0.2794)
			(stroke
				(width 0.1)
				(type default)
			)
			(layer "F.Fab")
		)
		(fp_line
			(start -0.67945 0.3048)
			(end -0.67945 -0.305054)
			(stroke
				(width 0.1)
				(type default)
			)
			(layer "F.Fab")
		)
		(fp_line
			(start -0.67945 -0.305054)
			(end -0.12065 -0.305054)
			(stroke
				(width 0.1)
				(type default)
			)
			(layer "F.Fab")
		)
		(pad "1" smd circle
			(at -0.40005 0 180)
			(size 0 0)
			(layers "F.Cu" "F.Mask" "F.Paste")
			(net "FAN_2_TACH_OL_R")
		)
		(pad "2" smd circle
			(at 0.40005 0 180)
			(size 0 0)
			(layers "F.Cu" "F.Mask" "F.Paste")
			(net "GND")
		)
	)
)
